# SCM (Grand Teton) — schematic netlist excerpt (pin names and nets, part order shuffled) for the footprints in the layout excerpt that follows; sources: Cadence DE-HDL packaged netlist, KiCad conversion of 12092022_DA0F0TMDCD0_F0T_Management_Board_D_brd_V3_OCP.brd

R160  Q_RES  33.2 1% CHIP  pkg 0402LF  page 13 : A = RST_RSMRST_N ; B = RST_RSMRST_R_N
R186  Q_RES  110 1% CHIP  pkg 0402LF  page 14 : A = I3C2_SPD_SCL ; B = I3C2_SCL_R

(kicad_pcb
	(version 20260206)
	(generator "pcbnew")
	(generator_version "10.0")
	(general
		(thickness 1.6)
		(legacy_teardrops no)
	)
	(paper "A4")
	(title_block
		(title "12092022_DA0F0TMDCD0_F0T_Management_Board_D_brd_V3_OCP.brd")
		(comment 1 "Grand Teton / footprints 186-187 of 1440")
	)
	(layers
		(0 "F.Cu" signal "TOP")
		(4 "In1.Cu" signal "GND")
		(6 "In2.Cu" signal "IN1")
		(8 "In3.Cu" signal "GND1")
		(10 "In4.Cu" signal "IN2")
		(12 "In5.Cu" signal "VCC")
		(14 "In6.Cu" signal "VCC1")
		(16 "In7.Cu" signal "IN3")
		(18 "In8.Cu" signal "GND2")
		(20 "In9.Cu" signal "IN4")
		(22 "In10.Cu" signal "GND3")
		(2 "B.Cu" signal "BOTTOM")
		(9 "F.Adhes" user "F.Adhesive")
		(11 "B.Adhes" user "B.Adhesive")
		(13 "F.Paste" user "Package Geometry/Pastemask Top")
		(15 "B.Paste" user "Package Geometry/Pastemask Bottom")
		(5 "F.SilkS" user "Ref Des/Silkscreen Top")
		(7 "B.SilkS" user "Ref Des/Silkscreen Bottom")
		(1 "F.Mask" user "Board Geometry/Soldermask Top")
		(3 "B.Mask" user "Board Geometry/Soldermask Bottom")
		(17 "Dwgs.User" user "User.Drawings")
		(19 "Cmts.User" user "User.Comments")
		(21 "Eco1.User" user "User.Eco1")
		(23 "Eco2.User" user "User.Eco2")
		(25 "Edge.Cuts" user "Board Geometry/Outline")
		(27 "Margin" user)
		(31 "F.CrtYd" user "Package Geometry/Place Bound Top")
		(29 "B.CrtYd" user "Package Geometry/Place Bound Bottom")
		(35 "F.Fab" user "Ref Des/Assembly Top")
		(33 "B.Fab" user "Ref Des/Assembly Bottom")
	)
	(footprint ""
		(layer "F.Cu")
		(at 44.193968 -65.776094 -90)
		(property "Reference" "R186"
			(at 0 0 270)
			(layer "F.SilkS")
			(hide yes)
			(effects
				(font
					(size 1.27 1.27)
				)
			)
		)
		(property "Value" ""
			(at 0 0 270)
			(layer "F.Fab")
			(effects
				(font
					(size 1.27 1.27)
				)
			)
		)
		(duplicate_pad_numbers_are_jumpers no)
		(fp_line
			(start -0.7874 0.4064)
			(end -0.7874 -0.4064)
			(stroke
				(width 0.1524)
				(type default)
			)
			(layer "F.SilkS")
		)
		(fp_line
			(start 0.7874 0.4064)
			(end -0.7874 0.4064)
			(stroke
				(width 0.1524)
				(type default)
			)
			(layer "F.SilkS")
		)
		(fp_line
			(start -0.7874 -0.4064)
			(end 0.7874 -0.4064)
			(stroke
				(width 0.1524)
				(type default)
			)
			(layer "F.SilkS")
		)
		(fp_line
			(start 0.7874 -0.4064)
			(end 0.7874 0.4064)
			(stroke
				(width 0.1524)
				(type default)
			)
			(layer "F.SilkS")
		)
		(fp_line
			(start -0.67945 0.3048)
			(end -0.67945 -0.305054)
			(stroke
				(width 0.1)
				(type default)
			)
			(layer "F.Fab")
		)
		(fp_line
			(start -0.12065 0.3048)
			(end -0.67945 0.3048)
			(stroke
				(width 0.1)
				(type default)
			)
			(layer "F.Fab")
		)
		(fp_line
			(start 0.120396 0.3048)
			(end 0.120396 0.2794)
			(stroke
				(width 0.1)
				(type default)
			)
			(layer "F.Fab")
		)
		(fp_line
			(start 0.67945 0.3048)
			(end 0.120396 0.3048)
			(stroke
				(width 0.1)
				(type default)
			)
			(layer "F.Fab")
		)
		(fp_line
			(start -0.12065 0.2794)
			(end -0.12065 0.3048)
			(stroke
				(width 0.1)
				(type default)
			)
			(layer "F.Fab")
		)
		(fp_line
			(start 0.120396 0.2794)
			(end -0.12065 0.2794)
			(stroke
				(width 0.1)
				(type default)
			)
			(layer "F.Fab")
		)
		(fp_line
			(start -0.12065 -0.2794)
			(end 0.12065 -0.2794)
			(stroke
				(width 0.1)
				(type default)
			)
			(layer "F.Fab")
		)
		(fp_line
			(start 0.12065 -0.2794)
			(end 0.12065 -0.3048)
			(stroke
				(width 0.1)
				(type default)
			)
			(layer "F.Fab")
		)
		(fp_line
			(start 0.12065 -0.3048)
			(end 0.67945 -0.3048)
			(stroke
				(width 0.1)
				(type default)
			)
			(layer "F.Fab")
		)
		(fp_line
			(start 0.67945 -0.3048)
			(end 0.67945 0.3048)
			(stroke
				(width 0.1)
				(type default)
			)
			(layer "F.Fab")
		)
		(fp_line
			(start -0.67945 -0.305054)
			(end -0.12065 -0.305054)
			(stroke
				(width 0.1)
				(type default)
			)
			(layer "F.Fab")
		)
		(fp_line
			(start -0.12065 -0.305054)
			(end -0.12065 -0.2794)
			(stroke
				(width 0.1)
				(type default)
			)
			(layer "F.Fab")
		)
		(pad "1" smd circle
			(at -0.40005 0 270)
			(size 0 0)
			(layers "F.Cu" "F.Mask" "F.Paste")
			(net "I3C2_SPD_SCL")
		)
		(pad "2" smd circle
			(at 0.40005 0 270)
			(size 0 0)
			(layers "F.Cu" "F.Mask" "F.Paste")
			(net "I3C2_SCL_R")
		)
	)
	(footprint ""
		(layer "F.Cu")
		(at 51.832002 -63.953644 -90)
		(property "Reference" "R160"
			(at 0 0 270)
			(layer "F.SilkS")
			(hide yes)
			(effects
				(font
					(size 1.27 1.27)
				)
			)
		)
		(property "Value" ""
			(at 0 0 270)
			(layer "F.Fab")
			(effects
				(font
					(size 1.27 1.27)
				)
			)
		)
		(duplicate_pad_numbers_are_jumpers no)
		(fp_line
			(start -0.7874 0.4064)
			(end -0.7874 -0.4064)
			(stroke
				(width 0.1524)
				(type default)
			)
			(layer "F.SilkS")
		)
		(fp_line
			(start 0.7874 0.4064)
			(end -0.7874 0.4064)
			(stroke
				(width 0.1524)
				(type default)
			)
			(layer "F.SilkS")
		)
		(fp_line
			(start -0.7874 -0.4064)
			(end 0.7874 -0.4064)
			(stroke
				(width 0.1524)
				(type default)
			)
			(layer "F.SilkS")
		)
		(fp_line
			(start 0.7874 -0.4064)
			(end 0.7874 0.4064)
			(stroke
				(width 0.1524)
				(type default)
			)
			(layer "F.SilkS")
		)
		(fp_line
			(start -0.67945 0.3048)
			(end -0.67945 -0.305054)
			(stroke
				(width 0.1)
				(type default)
			)
			(layer "F.Fab")
		)
		(fp_line
			(start -0.12065 0.3048)
			(end -0.67945 0.3048)
			(stroke
				(width 0.1)
				(type default)
			)
			(layer "F.Fab")
		)
		(fp_line
			(start 0.120396 0.3048)
			(end 0.120396 0.2794)
			(stroke
				(width 0.1)
				(type default)
			)
			(layer "F.Fab")
		)
		(fp_line
			(start 0.67945 0.3048)
			(end 0.120396 0.3048)
			(stroke
				(width 0.1)
				(type default)
			)
			(layer "F.Fab")
		)
		(fp_line
			(start -0.12065 0.2794)
			(end -0.12065 0.3048)
			(stroke
				(width 0.1)
				(type default)
			)
			(layer "F.Fab")
		)
		(fp_line
			(start 0.120396 0.2794)
			(end -0.12065 0.2794)
			(stroke
				(width 0.1)
				(type default)
			)
			(layer "F.Fab")
		)
		(fp_line
			(start -0.12065 -0.2794)
			(end 0.12065 -0.2794)
			(stroke
				(width 0.1)
				(type default)
			)
			(layer "F.Fab")
		)
		(fp_line
			(start 0.12065 -0.2794)
			(end 0.12065 -0.3048)
			(stroke
				(width 0.1)
				(type default)
			)
			(layer "F.Fab")
		)
		(fp_line
			(start 0.12065 -0.3048)
			(end 0.67945 -0.3048)
			(stroke
				(width 0.1)
				(type default)
			)
			(layer "F.Fab")
		)
		(fp_line
			(start 0.67945 -0.3048)
			(end 0.67945 0.3048)
			(stroke
				(width 0.1)
				(type default)
			)
			(layer "F.Fab")
		)
		(fp_line
			(start -0.67945 -0.305054)
			(end -0.12065 -0.305054)
			(stroke
				(width 0.1)
				(type default)
			)
			(layer "F.Fab")
		)
		(fp_line
			(start -0.12065 -0.305054)
			(end -0.12065 -0.2794)
			(stroke
				(width 0.1)
				(type default)
			)
			(layer "F.Fab")
		)
		(pad "1" smd circle
			(at -0.40005 0 270)
			(size 0 0)
			(layers "F.Cu" "F.Mask" "F.Paste")
			(net "RST_RSMRST_N")
		)
		(pad "2" smd circle
			(at 0.40005 0 270)
			(size 0 0)
			(layers "F.Cu" "F.Mask" "F.Paste")
			(net "RST_RSMRST_R_N")
		)
	)
)
